(kicad_pcb
	(version 20241229)
	(generator "pcbnew")
	(generator_version "9.0")
	(general
		(thickness 1.599998)
		(legacy_teardrops no)
	)
	(paper "A4")
	(title_block
		(date "2023-02-12")
		(rev "1.1.5")
		(comment 9 "footprints 261-267 of 473")
	)
	(layers
		(0 "F.Cu" signal)
		(4 "In1.Cu" power "In1.GND")
		(6 "In2.Cu" signal)
		(8 "In3.Cu" power "In3.GND")
		(10 "In4.Cu" power "In4.VCC")
		(12 "In5.Cu" signal)
		(14 "In6.Cu" power "In6.VCC")
		(2 "B.Cu" signal)
		(9 "F.Adhes" user "F.Adhesive")
		(11 "B.Adhes" user "B.Adhesive")
		(13 "F.Paste" user)
		(15 "B.Paste" user)
		(5 "F.SilkS" user "F.Silkscreen")
		(7 "B.SilkS" user "B.Silkscreen")
		(1 "F.Mask" user)
		(3 "B.Mask" user)
		(17 "Dwgs.User" user "User.Drawings")
		(19 "Cmts.User" user "User.Comments")
		(21 "Eco1.User" user "User.Eco1")
		(23 "Eco2.User" user "User.Eco2")
		(25 "Edge.Cuts" user)
		(27 "Margin" user)
		(31 "F.CrtYd" user "F.Courtyard")
		(29 "B.CrtYd" user "B.Courtyard")
		(35 "F.Fab" user)
		(33 "B.Fab" user)
	)
	(footprint "antmicro-footprints:R_0805_2012Metric"
		(layer "F.Cu")
		(at 126.34 81.274)
		(property "Reference" "R146"
			(at 1.56 0.426 0)
			(layer "F.SilkS")
			(effects
				(font
					(size 0.7 0.7)
					(thickness 0.15)
				)
				(justify left bottom)
			)
		)
		(property "Value" "R_0R_0805"
			(at 0 1.8 0)
			(layer "F.Fab")
			(effects
				(font
					(size 0.7 0.7)
					(thickness 0.15)
				)
				(justify left bottom)
			)
		)
		(property "Description" "0R resistor in 0805 package with unspecified tolerance"
			(at 0 0 0)
			(layer "F.Fab")
			(hide yes)
			(effects
				(font
					(size 1.27 1.27)
					(thickness 0.15)
				)
			)
		)
		(property "Author" "Antmicro"
			(at 0 0 0)
			(layer "F.Fab")
			(hide yes)
			(effects
				(font
					(size 1 1)
					(thickness 0.15)
				)
			)
		)
		(property "Current" "2.5A"
			(at 0 0 0)
			(layer "F.Fab")
			(hide yes)
			(effects
				(font
					(size 1 1)
					(thickness 0.15)
				)
			)
		)
		(property "License" "Apache-2.0"
			(at 0 0 0)
			(layer "F.Fab")
			(hide yes)
			(effects
				(font
					(size 1 1)
					(thickness 0.15)
				)
			)
		)
		(property "MPN" "CRCW08050000Z0EA"
			(at 0 0 0)
			(layer "F.Fab")
			(hide yes)
			(effects
				(font
					(size 1 1)
					(thickness 0.15)
				)
			)
		)
		(property "Manufacturer" "Vishay"
			(at 0 0 0)
			(layer "F.Fab")
			(hide yes)
			(effects
				(font
					(size 1 1)
					(thickness 0.15)
				)
			)
		)
		(property "Tolerance" ""
			(at 0 0 0)
			(layer "F.Fab")
			(hide yes)
			(effects
				(font
					(size 1 1)
					(thickness 0.15)
				)
			)
		)
		(property "Val" "0R"
			(at 0 0 0)
			(layer "F.Fab")
			(hide yes)
			(effects
				(font
					(size 1 1)
					(thickness 0.15)
				)
			)
		)
		(sheetname "Supply")
		(sheetfile "supply.kicad_sch")
		(attr smd)
		(fp_line
			(start -0.32 0.699)
			(end 0.28 0.699)
			(stroke
				(width 0.15)
				(type solid)
			)
			(layer "F.SilkS")
		)
		(fp_line
			(start -0.3 -0.701)
			(end 0.298 -0.701)
			(stroke
				(width 0.15)
				(type solid)
			)
			(layer "F.SilkS")
		)
		(fp_rect
			(start -1.75 -0.85)
			(end 1.75 0.85)
			(stroke
				(width 0.05)
				(type solid)
			)
			(fill no)
			(layer "F.CrtYd")
		)
		(fp_line
			(start -0.951 -0.682)
			(end 0.949 -0.682)
			(stroke
				(width 0.15)
				(type solid)
			)
			(layer "F.Fab")
		)
		(fp_line
			(start -0.951 -0.677)
			(end -0.951 0.675)
			(stroke
				(width 0.15)
				(type solid)
			)
			(layer "F.Fab")
		)
		(fp_line
			(start -0.951 0.68)
			(end 0.949 0.68)
			(stroke
				(width 0.15)
				(type solid)
			)
			(layer "F.Fab")
		)
		(fp_line
			(start 0.949 -0.677)
			(end 0.949 0.675)
			(stroke
				(width 0.15)
				(type solid)
			)
			(layer "F.Fab")
		)
		(pad "1" smd roundrect
			(at -1.1 -0.001)
			(size 1 1.4)
			(layers "F.Cu" "F.Mask" "F.Paste")
			(roundrect_rratio 0.15)
			(net 587 "/Supply/1V1_REG")
			(pintype "passive")
		)
		(pad "2" smd roundrect
			(at 1.1 -0.001)
			(size 1 1.4)
			(layers "F.Cu" "F.Mask" "F.Paste")
			(roundrect_rratio 0.15)
			(net 461 "1V1_SYS")
			(pintype "passive")
		)
	)
	(footprint "antmicro-footprints:TP_SMD_1mm"
		(layer "F.Cu")
		(at 144.7 90.1498)
		(property "Reference" "TP17"
			(at -1.4 -7.479898 0)
			(layer "F.SilkS")
			(effects
				(font
					(size 0.7 0.7)
					(thickness 0.15)
				)
				(justify left bottom)
			)
		)
		(property "Value" "TP_1mm_SMD"
			(at 0 1.4 0)
			(layer "F.Fab")
			(effects
				(font
					(size 0.7 0.7)
					(thickness 0.15)
				)
				(justify left bottom)
			)
		)
		(property "Description" "Test Point 1mm"
			(at 0 0 0)
			(layer "F.Fab")
			(hide yes)
			(effects
				(font
					(size 1.27 1.27)
					(thickness 0.15)
				)
			)
		)
		(property "Author" "Antmicro"
			(at 0 0 0)
			(layer "F.Fab")
			(hide yes)
			(effects
				(font
					(size 1 1)
					(thickness 0.15)
				)
			)
		)
		(property "License" "Apache-2.0"
			(at 0 0 0)
			(layer "F.Fab")
			(hide yes)
			(effects
				(font
					(size 1 1)
					(thickness 0.15)
				)
			)
		)
		(property "MPN" ""
			(at 0 0 0)
			(layer "F.Fab")
			(hide yes)
			(effects
				(font
					(size 1 1)
					(thickness 0.15)
				)
			)
		)
		(property "Manufacturer" ""
			(at 0 0 0)
			(layer "F.Fab")
			(hide yes)
			(effects
				(font
					(size 1 1)
					(thickness 0.15)
				)
			)
		)
		(sheetname "Supply")
		(sheetfile "supply.kicad_sch")
		(attr exclude_from_pos_files)
		(pad "1" smd circle
			(at 0 0)
			(size 1 1)
			(layers "F.Cu" "F.Mask")
			(net 602 "1V2_SYS")
			(pinfunction "1")
			(pintype "passive")
		)
	)
	(footprint "antmicro-footprints:C_0603_1608Metric"
		(layer "F.Cu")
		(at 125.3 63.1 180)
		(descr "Capacitor SMD 0603")
		(tags "capacitor 0603")
		(property "Reference" "C184"
			(at 3.9 -0.35 180)
			(layer "F.SilkS")
			(effects
				(font
					(size 0.7 0.7)
					(thickness 0.15)
				)
				(justify left bottom)
			)
		)
		(property "Value" "C_1u_0603"
			(at 0 1.6 180)
			(layer "F.Fab")
			(effects
				(font
					(size 0.7 0.7)
					(thickness 0.15)
				)
				(justify left bottom)
			)
		)
		(property "Description" " "
			(at 0 0 180)
			(layer "F.Fab")
			(hide yes)
			(effects
				(font
					(size 1.27 1.27)
					(thickness 0.15)
				)
			)
		)
		(property "Author" "Antmicro"
			(at 250.6 126.2 0)
			(layer "F.Fab")
			(hide yes)
			(effects
				(font
					(size 1 1)
					(thickness 0.15)
				)
			)
		)
		(property "Dielectric" ""
			(at 250.6 126.2 0)
			(layer "F.Fab")
			(hide yes)
			(effects
				(font
					(size 1 1)
					(thickness 0.15)
				)
			)
		)
		(property "License" "Apache-2.0"
			(at 250.6 126.2 0)
			(layer "F.Fab")
			(hide yes)
			(effects
				(font
					(size 1 1)
					(thickness 0.15)
				)
			)
		)
		(property "MPN" "0603YD105KAT2A"
			(at 250.6 126.2 0)
			(layer "F.Fab")
			(hide yes)
			(effects
				(font
					(size 1 1)
					(thickness 0.15)
				)
			)
		)
		(property "Manufacturer" "Walsin"
			(at 250.6 126.2 0)
			(layer "F.Fab")
			(hide yes)
			(effects
				(font
					(size 1 1)
					(thickness 0.15)
				)
			)
		)
		(property "Val" "1u"
			(at 250.6 126.2 0)
			(layer "F.Fab")
			(hide yes)
			(effects
				(font
					(size 1 1)
					(thickness 0.15)
				)
			)
		)
		(property "Voltage" ""
			(at 250.6 126.2 0)
			(layer "F.Fab")
			(hide yes)
			(effects
				(font
					(size 1 1)
					(thickness 0.15)
				)
			)
		)
		(sheetname "Supply")
		(sheetfile "supply.kicad_sch")
		(attr exclude_from_pos_files exclude_from_bom dnp)
		(fp_line
			(start -0.3 0.3)
			(end 0.3 0.3)
			(stroke
				(width 0.15)
				(type solid)
			)
			(layer "F.SilkS")
		)
		(fp_line
			(start -0.3 -0.3)
			(end 0.3 -0.3)
			(stroke
				(width 0.15)
				(type solid)
			)
			(layer "F.SilkS")
		)
		(fp_rect
			(start -1.24 -0.7)
			(end 1.24 0.7)
			(stroke
				(width 0.05)
				(type solid)
			)
			(fill no)
			(layer "F.CrtYd")
		)
		(fp_rect
			(start -0.8 -0.4)
			(end 0.8 0.4)
			(stroke
				(width 0.15)
				(type solid)
			)
			(fill no)
			(layer "F.Fab")
		)
		(pad "1" smd roundrect
			(at -0.7 0 180)
			(size 0.6 0.8)
			(layers "F.Cu" "F.Mask" "F.Paste")
			(roundrect_rratio 0.2)
			(net 463 "VCC5V0_INT")
			(pintype "passive")
		)
		(pad "2" smd roundrect
			(at 0.7 0 180)
			(size 0.6 0.8)
			(layers "F.Cu" "F.Mask" "F.Paste")
			(roundrect_rratio 0.2)
			(net 5 "GND")
			(pintype "passive")
		)
	)
	(footprint "antmicro-footprints:C_0805_2012Metric"
		(layer "F.Cu")
		(at 112.7492 111.975 90)
		(descr "Capacitor SMD 0805")
		(tags "capacitor SMD 0805")
		(property "Reference" "C126"
			(at 1.65 0.3508 90)
			(layer "F.SilkS")
			(effects
				(font
					(size 0.7 0.7)
					(thickness 0.15)
				)
				(justify left bottom)
			)
		)
		(property "Value" "C_22u_0805_16V"
			(at 0 1.947 90)
			(layer "F.Fab")
			(effects
				(font
					(size 0.7 0.7)
					(thickness 0.15)
				)
				(justify left bottom)
			)
		)
		(property "Description" " "
			(at 0 0 90)
			(layer "F.Fab")
			(hide yes)
			(effects
				(font
					(size 1.27 1.27)
					(thickness 0.15)
				)
			)
		)
		(property "Author" "Antmicro"
			(at 224.7242 -0.7742 0)
			(layer "F.Fab")
			(hide yes)
			(effects
				(font
					(size 1 1)
					(thickness 0.15)
				)
			)
		)
		(property "Dielectric" ""
			(at 224.7242 -0.7742 0)
			(layer "F.Fab")
			(hide yes)
			(effects
				(font
					(size 1 1)
					(thickness 0.15)
				)
			)
		)
		(property "License" "Apache-2.0"
			(at 224.7242 -0.7742 0)
			(layer "F.Fab")
			(hide yes)
			(effects
				(font
					(size 1 1)
					(thickness 0.15)
				)
			)
		)
		(property "MPN" "GRT21BR61C226ME13L"
			(at 224.7242 -0.7742 0)
			(layer "F.Fab")
			(hide yes)
			(effects
				(font
					(size 1 1)
					(thickness 0.15)
				)
			)
		)
		(property "Manufacturer" "Murata"
			(at 224.7242 -0.7742 0)
			(layer "F.Fab")
			(hide yes)
			(effects
				(font
					(size 1 1)
					(thickness 0.15)
				)
			)
		)
		(property "Val" "22u/16V"
			(at 224.7242 -0.7742 0)
			(layer "F.Fab")
			(hide yes)
			(effects
				(font
					(size 1 1)
					(thickness 0.15)
				)
			)
		)
		(property "Voltage" ""
			(at 224.7242 -0.7742 0)
			(layer "F.Fab")
			(hide yes)
			(effects
				(font
					(size 1 1)
					(thickness 0.15)
				)
			)
		)
		(sheetname "Supply")
		(sheetfile "supply.kicad_sch")
		(attr smd)
		(fp_line
			(start -0.3 -0.8)
			(end 0.3 -0.8)
			(stroke
				(width 0.15)
				(type solid)
			)
			(layer "F.SilkS")
		)
		(fp_line
			(start -0.3 0.8)
			(end 0.3 0.8)
			(stroke
				(width 0.15)
				(type solid)
			)
			(layer "F.SilkS")
		)
		(fp_rect
			(start -1.9 -0.93)
			(end 1.9 0.93)
			(stroke
				(width 0.05)
				(type solid)
			)
			(fill no)
			(layer "F.CrtYd")
		)
		(fp_rect
			(start -0.95 -0.675)
			(end 0.95 0.675)
			(stroke
				(width 0.15)
				(type solid)
			)
			(fill no)
			(layer "F.Fab")
		)
		(pad "1" smd rect
			(at -1.05 0 90)
			(size 1.2 1.2)
			(layers "F.Cu" "F.Mask" "F.Paste")
			(net 224 "VIN")
			(pintype "passive")
		)
		(pad "2" smd rect
			(at 1.05 0 90)
			(size 1.2 1.2)
			(layers "F.Cu" "F.Mask" "F.Paste")
			(net 5 "GND")
			(pintype "passive")
		)
	)
	(footprint "antmicro-footprints:C_0402_1005Metric"
		(layer "F.Cu")
		(at 135.6 65.2 -90)
		(descr "Capacitor SMD 0402")
		(tags "capacitor SMD 0402")
		(property "Reference" "C136"
			(at 3.7 -0.4 270)
			(layer "F.SilkS")
			(effects
				(font
					(size 0.7 0.7)
					(thickness 0.15)
				)
				(justify left bottom)
			)
		)
		(property "Value" "C_100n_6V3_0402"
			(at 0 1.4 270)
			(layer "F.Fab")
			(effects
				(font
					(size 0.7 0.7)
					(thickness 0.15)
				)
				(justify left bottom)
			)
		)
		(property "Description" " "
			(at 0 0 270)
			(layer "F.Fab")
			(hide yes)
			(effects
				(font
					(size 1.27 1.27)
					(thickness 0.15)
				)
			)
		)
		(property "Author" "Antmicro"
			(at 70.4 200.8 0)
			(layer "F.Fab")
			(hide yes)
			(effects
				(font
					(size 1 1)
					(thickness 0.15)
				)
			)
		)
		(property "Dielectric" ""
			(at 70.4 200.8 0)
			(layer "F.Fab")
			(hide yes)
			(effects
				(font
					(size 1 1)
					(thickness 0.15)
				)
			)
		)
		(property "License" "Apache-2.0"
			(at 70.4 200.8 0)
			(layer "F.Fab")
			(hide yes)
			(effects
				(font
					(size 1 1)
					(thickness 0.15)
				)
			)
		)
		(property "MPN" "0402X104K6R3CT"
			(at 70.4 200.8 0)
			(layer "F.Fab")
			(hide yes)
			(effects
				(font
					(size 1 1)
					(thickness 0.15)
				)
			)
		)
		(property "Manufacturer" "Walsin"
			(at 70.4 200.8 0)
			(layer "F.Fab")
			(hide yes)
			(effects
				(font
					(size 1 1)
					(thickness 0.15)
				)
			)
		)
		(property "Val" "100n"
			(at 70.4 200.8 0)
			(layer "F.Fab")
			(hide yes)
			(effects
				(font
					(size 1 1)
					(thickness 0.15)
				)
			)
		)
		(property "Voltage" ""
			(at 70.4 200.8 0)
			(layer "F.Fab")
			(hide yes)
			(effects
				(font
					(size 1 1)
					(thickness 0.15)
				)
			)
		)
		(sheetname "Supply")
		(sheetfile "supply.kicad_sch")
		(attr smd)
		(fp_rect
			(start -0.94 -0.47)
			(end 0.94 0.47)
			(stroke
				(width 0.05)
				(type solid)
			)
			(fill no)
			(layer "F.CrtYd")
		)
		(fp_rect
			(start -0.499 -0.249)
			(end 0.499 0.249)
			(stroke
				(width 0.15)
				(type solid)
			)
			(fill no)
			(layer "F.Fab")
		)
		(pad "1" smd roundrect
			(at -0.484 0 270)
			(size 0.59 0.64)
			(layers "F.Cu" "F.Mask" "F.Paste")
			(roundrect_rratio 0.25)
			(net 639 "/Supply/0V6_CP")
			(pintype "passive")
		)
		(pad "2" smd roundrect
			(at 0.484 0 270)
			(size 0.59 0.64)
			(layers "F.Cu" "F.Mask" "F.Paste")
			(roundrect_rratio 0.25)
			(net 5 "GND")
			(pintype "passive")
		)
	)
	(footprint "antmicro-footprints:C_0402_1005Metric"
		(layer "F.Cu")
		(at 115.975 98.299)
		(descr "Capacitor SMD 0402")
		(tags "capacitor SMD 0402")
		(property "Reference" "C157"
			(at -3.575 0.401 0)
			(layer "F.SilkS")
			(effects
				(font
					(size 0.7 0.7)
					(thickness 0.15)
				)
				(justify left bottom)
			)
		)
		(property "Value" "C_100n_6V3_0402"
			(at 0 1.4 0)
			(layer "F.Fab")
			(effects
				(font
					(size 0.7 0.7)
					(thickness 0.15)
				)
				(justify left bottom)
			)
		)
		(property "Description" " "
			(at 0 0 0)
			(layer "F.Fab")
			(hide yes)
			(effects
				(font
					(size 1.27 1.27)
					(thickness 0.15)
				)
			)
		)
		(property "Author" "Antmicro"
			(at 0 0 0)
			(layer "F.Fab")
			(hide yes)
			(effects
				(font
					(size 1 1)
					(thickness 0.15)
				)
			)
		)
		(property "Dielectric" ""
			(at 0 0 0)
			(layer "F.Fab")
			(hide yes)
			(effects
				(font
					(size 1 1)
					(thickness 0.15)
				)
			)
		)
		(property "License" "Apache-2.0"
			(at 0 0 0)
			(layer "F.Fab")
			(hide yes)
			(effects
				(font
					(size 1 1)
					(thickness 0.15)
				)
			)
		)
		(property "MPN" "0402X104K6R3CT"
			(at 0 0 0)
			(layer "F.Fab")
			(hide yes)
			(effects
				(font
					(size 1 1)
					(thickness 0.15)
				)
			)
		)
		(property "Manufacturer" "Walsin"
			(at 0 0 0)
			(layer "F.Fab")
			(hide yes)
			(effects
				(font
					(size 1 1)
					(thickness 0.15)
				)
			)
		)
		(property "Val" "100n"
			(at 0 0 0)
			(layer "F.Fab")
			(hide yes)
			(effects
				(font
					(size 1 1)
					(thickness 0.15)
				)
			)
		)
		(property "Voltage" ""
			(at 0 0 0)
			(layer "F.Fab")
			(hide yes)
			(effects
				(font
					(size 1 1)
					(thickness 0.15)
				)
			)
		)
		(sheetname "Supply")
		(sheetfile "supply.kicad_sch")
		(attr smd)
		(fp_rect
			(start -0.94 -0.47)
			(end 0.94 0.47)
			(stroke
				(width 0.05)
				(type solid)
			)
			(fill no)
			(layer "F.CrtYd")
		)
		(fp_rect
			(start -0.499 -0.249)
			(end 0.499 0.249)
			(stroke
				(width 0.15)
				(type solid)
			)
			(fill no)
			(layer "F.Fab")
		)
		(pad "1" smd roundrect
			(at -0.484 0)
			(size 0.59 0.64)
			(layers "F.Cu" "F.Mask" "F.Paste")
			(roundrect_rratio 0.25)
			(net 575 "/Supply/3V3_SW")
			(pintype "passive")
		)
		(pad "2" smd roundrect
			(at 0.484 0)
			(size 0.59 0.64)
			(layers "F.Cu" "F.Mask" "F.Paste")
			(roundrect_rratio 0.25)
			(net 574 "/Supply/3V3_BST")
			(pintype "passive")
		)
	)
	(footprint "antmicro-footprints:R_0805_2012Metric"
		(layer "F.Cu")
		(at 126.0825 93.749)
		(property "Reference" "R147"
			(at 1.6175 0.351 0)
			(layer "F.SilkS")
			(effects
				(font
					(size 0.7 0.7)
					(thickness 0.15)
				)
				(justify left bottom)
			)
		)
		(property "Value" "R_0R_0805"
			(at 0 1.8 0)
			(layer "F.Fab")
			(effects
				(font
					(size 0.7 0.7)
					(thickness 0.15)
				)
				(justify left bottom)
			)
		)
		(property "Description" "0R resistor in 0805 package with unspecified tolerance"
			(at 0 0 0)
			(layer "F.Fab")
			(hide yes)
			(effects
				(font
					(size 1.27 1.27)
					(thickness 0.15)
				)
			)
		)
		(property "Author" "Antmicro"
			(at 0 0 0)
			(layer "F.Fab")
			(hide yes)
			(effects
				(font
					(size 1 1)
					(thickness 0.15)
				)
			)
		)
		(property "Current" "2.5A"
			(at 0 0 0)
			(layer "F.Fab")
			(hide yes)
			(effects
				(font
					(size 1 1)
					(thickness 0.15)
				)
			)
		)
		(property "License" "Apache-2.0"
			(at 0 0 0)
			(layer "F.Fab")
			(hide yes)
			(effects
				(font
					(size 1 1)
					(thickness 0.15)
				)
			)
		)
		(property "MPN" "CRCW08050000Z0EA"
			(at 0 0 0)
			(layer "F.Fab")
			(hide yes)
			(effects
				(font
					(size 1 1)
					(thickness 0.15)
				)
			)
		)
		(property "Manufacturer" "Vishay"
			(at 0 0 0)
			(layer "F.Fab")
			(hide yes)
			(effects
				(font
					(size 1 1)
					(thickness 0.15)
				)
			)
		)
		(property "Tolerance" ""
			(at 0 0 0)
			(layer "F.Fab")
			(hide yes)
			(effects
				(font
					(size 1 1)
					(thickness 0.15)
				)
			)
		)
		(property "Val" "0R"
			(at 0 0 0)
			(layer "F.Fab")
			(hide yes)
			(effects
				(font
					(size 1 1)
					(thickness 0.15)
				)
			)
		)
		(sheetname "Supply")
		(sheetfile "supply.kicad_sch")
		(attr smd)
		(fp_line
			(start -0.32 0.699)
			(end 0.28 0.699)
			(stroke
				(width 0.15)
				(type solid)
			)
			(layer "F.SilkS")
		)
		(fp_line
			(start -0.3 -0.701)
			(end 0.298 -0.701)
			(stroke
				(width 0.15)
				(type solid)
			)
			(layer "F.SilkS")
		)
		(fp_rect
			(start -1.75 -0.85)
			(end 1.75 0.85)
			(stroke
				(width 0.05)
				(type solid)
			)
			(fill no)
			(layer "F.CrtYd")
		)
		(fp_line
			(start -0.951 -0.682)
			(end 0.949 -0.682)
			(stroke
				(width 0.15)
				(type solid)
			)
			(layer "F.Fab")
		)
		(fp_line
			(start -0.951 -0.677)
			(end -0.951 0.675)
			(stroke
				(width 0.15)
				(type solid)
			)
			(layer "F.Fab")
		)
		(fp_line
			(start -0.951 0.68)
			(end 0.949 0.68)
			(stroke
				(width 0.15)
				(type solid)
			)
			(layer "F.Fab")
		)
		(fp_line
			(start 0.949 -0.677)
			(end 0.949 0.675)
			(stroke
				(width 0.15)
				(type solid)
			)
			(layer "F.Fab")
		)
		(pad "1" smd roundrect
			(at -1.1 -0.001)
			(size 1 1.4)
			(layers "F.Cu" "F.Mask" "F.Paste")
			(roundrect_rratio 0.15)
			(net 588 "/Supply/1V0_REG")
			(pintype "passive")
		)
		(pad "2" smd roundrect
			(at 1.1 -0.001)
			(size 1 1.4)
			(layers "F.Cu" "F.Mask" "F.Paste")
			(roundrect_rratio 0.15)
			(net 465 "1V0_SYS")
			(pintype "passive")
		)
	)
)
